# S9S_MB_2U (Grand Teton) — schematic netlist excerpt (pin names and nets, part order shuffled) for the footprints in the layout excerpt that follows; sources: Cadence DE-HDL packaged netlist, KiCad conversion of 03242023_DA0F0TMBIJ0_F0T_Motherboard_J_brd_V01_OCP.brd

C882  Q_CAP_DIFFBUS  DIFF BUS_0.22UF 6.3V 20% X6S  pkg C0201  page 174 : \1\ = P5E_CPU0_PE3_TX_C_DN<9> ; \2\ = P5E_CPU0_PE3_TX_DN<9>
R3338  Q_RES  0 5% CHIP  pkg 0402LF  page 212 : A = CLK_100M_GPU_FPGA_DN_R ; B = CLK_100M_GPU_FPGA_DN
C250  Q_CAP  47UF 4V 20% X6S  pkg C0805  page 77 : A = PVCCIN_CPU1 ; B = GND

(kicad_pcb
	(version 20260206)
	(generator "pcbnew")
	(generator_version "10.0")
	(general
		(thickness 1.6)
		(legacy_teardrops no)
	)
	(paper "A4")
	(title_block
		(title "03242023_DA0F0TMBIJ0_F0T_Motherboard_J_brd_V01_OCP.brd")
		(comment 1 "Grand Teton / footprints 2760-2762 of 6105")
	)
	(layers
		(0 "F.Cu" signal "TOP")
		(4 "In1.Cu" signal "GND")
		(6 "In2.Cu" signal "IN1")
		(8 "In3.Cu" signal "GND1")
		(10 "In4.Cu" signal "IN2")
		(12 "In5.Cu" signal "GND2")
		(14 "In6.Cu" signal "IN3")
		(16 "In7.Cu" signal "GND3")
		(18 "In8.Cu" signal "VCC")
		(20 "In9.Cu" signal "VCC1")
		(22 "In10.Cu" signal "GND4")
		(24 "In11.Cu" signal "IN4")
		(26 "In12.Cu" signal "GND5")
		(28 "In13.Cu" signal "IN5")
		(30 "In14.Cu" signal "GND6")
		(32 "In15.Cu" signal "IN6")
		(34 "In16.Cu" signal "GND7")
		(2 "B.Cu" signal "BOTTOM")
		(9 "F.Adhes" user "F.Adhesive")
		(11 "B.Adhes" user "B.Adhesive")
		(13 "F.Paste" user "Package Geometry/Pastemask Top")
		(15 "B.Paste" user "Package Geometry/Pastemask Bottom")
		(5 "F.SilkS" user "Ref Des/Silkscreen Top")
		(7 "B.SilkS" user "Ref Des/Silkscreen Bottom")
		(1 "F.Mask" user "Board Geometry/Soldermask Top")
		(3 "B.Mask" user "Board Geometry/Soldermask Bottom")
		(17 "Dwgs.User" user "User.Drawings")
		(19 "Cmts.User" user "User.Comments")
		(21 "Eco1.User" user "User.Eco1")
		(23 "Eco2.User" user "User.Eco2")
		(25 "Edge.Cuts" user "Board Geometry/Outline")
		(27 "Margin" user)
		(31 "F.CrtYd" user "Package Geometry/Place Bound Top")
		(29 "B.CrtYd" user "Package Geometry/Place Bound Bottom")
		(35 "F.Fab" user "Ref Des/Assembly Top")
		(33 "B.Fab" user "Ref Des/Assembly Bottom")
	)
	(footprint ""
		(layer "F.Cu")
		(at 230.248206 -246.693436 180)
		(property "Reference" "R3338"
			(at 0 0 180)
			(layer "F.SilkS")
			(hide yes)
			(effects
				(font
					(size 1.27 1.27)
				)
			)
		)
		(property "Value" ""
			(at 0 0 180)
			(layer "F.Fab")
			(effects
				(font
					(size 1.27 1.27)
				)
			)
		)
		(duplicate_pad_numbers_are_jumpers no)
		(fp_line
			(start 0.7874 0.4064)
			(end -0.7874 0.4064)
			(stroke
				(width 0.1524)
				(type default)
			)
			(layer "F.SilkS")
		)
		(fp_line
			(start 0.7874 -0.4064)
			(end 0.7874 0.4064)
			(stroke
				(width 0.1524)
				(type default)
			)
			(layer "F.SilkS")
		)
		(fp_line
			(start -0.7874 0.4064)
			(end -0.7874 -0.4064)
			(stroke
				(width 0.1524)
				(type default)
			)
			(layer "F.SilkS")
		)
		(fp_line
			(start -0.7874 -0.4064)
			(end 0.7874 -0.4064)
			(stroke
				(width 0.1524)
				(type default)
			)
			(layer "F.SilkS")
		)
		(fp_line
			(start 0.67945 0.3048)
			(end 0.120396 0.3048)
			(stroke
				(width 0.1)
				(type default)
			)
			(layer "F.Fab")
		)
		(fp_line
			(start 0.67945 -0.3048)
			(end 0.67945 0.3048)
			(stroke
				(width 0.1)
				(type default)
			)
			(layer "F.Fab")
		)
		(fp_line
			(start 0.12065 -0.2794)
			(end 0.12065 -0.3048)
			(stroke
				(width 0.1)
				(type default)
			)
			(layer "F.Fab")
		)
		(fp_line
			(start 0.12065 -0.3048)
			(end 0.67945 -0.3048)
			(stroke
				(width 0.1)
				(type default)
			)
			(layer "F.Fab")
		)
		(fp_line
			(start 0.120396 0.3048)
			(end 0.120396 0.2794)
			(stroke
				(width 0.1)
				(type default)
			)
			(layer "F.Fab")
		)
		(fp_line
			(start 0.120396 0.2794)
			(end -0.12065 0.2794)
			(stroke
				(width 0.1)
				(type default)
			)
			(layer "F.Fab")
		)
		(fp_line
			(start -0.12065 0.3048)
			(end -0.67945 0.3048)
			(stroke
				(width 0.1)
				(type default)
			)
			(layer "F.Fab")
		)
		(fp_line
			(start -0.12065 0.2794)
			(end -0.12065 0.3048)
			(stroke
				(width 0.1)
				(type default)
			)
			(layer "F.Fab")
		)
		(fp_line
			(start -0.12065 -0.2794)
			(end 0.12065 -0.2794)
			(stroke
				(width 0.1)
				(type default)
			)
			(layer "F.Fab")
		)
		(fp_line
			(start -0.12065 -0.305054)
			(end -0.12065 -0.2794)
			(stroke
				(width 0.1)
				(type default)
			)
			(layer "F.Fab")
		)
		(fp_line
			(start -0.67945 0.3048)
			(end -0.67945 -0.305054)
			(stroke
				(width 0.1)
				(type default)
			)
			(layer "F.Fab")
		)
		(fp_line
			(start -0.67945 -0.305054)
			(end -0.12065 -0.305054)
			(stroke
				(width 0.1)
				(type default)
			)
			(layer "F.Fab")
		)
		(pad "1" smd circle
			(at -0.40005 0 180)
			(size 0 0)
			(layers "F.Cu" "F.Mask" "F.Paste")
			(net "CLK_100M_GPU_FPGA_DN_R")
		)
		(pad "2" smd circle
			(at 0.40005 0 180)
			(size 0 0)
			(layers "F.Cu" "F.Mask" "F.Paste")
			(net "CLK_100M_GPU_FPGA_DN")
		)
	)
	(footprint ""
		(layer "F.Cu")
		(at 391.12317 -408.517344 -90)
		(property "Reference" "C882"
			(at 0 0 270)
			(layer "F.SilkS")
			(hide yes)
			(effects
				(font
					(size 1.27 1.27)
				)
			)
		)
		(property "Value" ""
			(at 0 0 270)
			(layer "F.Fab")
			(effects
				(font
					(size 1.27 1.27)
				)
			)
		)
		(duplicate_pad_numbers_are_jumpers no)
		(fp_line
			(start -0.299974 0.150114)
			(end -0.299974 -0.150114)
			(stroke
				(width 0.1)
				(type default)
			)
			(layer "F.Fab")
		)
		(fp_line
			(start 0.299974 0.150114)
			(end -0.299974 0.150114)
			(stroke
				(width 0.1)
				(type default)
			)
			(layer "F.Fab")
		)
		(fp_line
			(start -0.299974 -0.150114)
			(end 0.299974 -0.150114)
			(stroke
				(width 0.1)
				(type default)
			)
			(layer "F.Fab")
		)
		(fp_line
			(start 0.299974 -0.150114)
			(end 0.299974 0.150114)
			(stroke
				(width 0.1)
				(type default)
			)
			(layer "F.Fab")
		)
		(pad "1" smd rect
			(at -0.2667 0 270)
			(size 0.3048 0.381)
			(layers "F.Cu" "F.Mask" "F.Paste")
			(net "P5E_CPU0_PE3_TX_C_DN<9>")
		)
		(pad "2" smd rect
			(at 0.2667 0 270)
			(size 0.3048 0.381)
			(layers "F.Cu" "F.Mask" "F.Paste")
			(net "P5E_CPU0_PE3_TX_DN<9>")
		)
	)
	(footprint ""
		(layer "F.Cu")
		(at 105.39222 -296.05478 180)
		(property "Reference" "C250"
			(at 0 0 180)
			(layer "F.SilkS")
			(hide yes)
			(effects
				(font
					(size 1.27 1.27)
				)
			)
		)
		(property "Value" ""
			(at 0 0 180)
			(layer "F.Fab")
			(effects
				(font
					(size 1.27 1.27)
				)
			)
		)
		(duplicate_pad_numbers_are_jumpers no)
		(fp_line
			(start 1.524 0.762)
			(end -1.524 0.762)
			(stroke
				(width 0.1524)
				(type default)
			)
			(layer "F.SilkS")
		)
		(fp_line
			(start 1.524 -0.762)
			(end 1.524 0.762)
			(stroke
				(width 0.1524)
				(type default)
			)
			(layer "F.SilkS")
		)
		(fp_line
			(start -1.524 0.762)
			(end -1.524 -0.762)
			(stroke
				(width 0.1524)
				(type default)
			)
			(layer "F.SilkS")
		)
		(fp_line
			(start -1.524 -0.762)
			(end 1.524 -0.762)
			(stroke
				(width 0.1524)
				(type default)
			)
			(layer "F.SilkS")
		)
		(fp_line
			(start 1.1049 0.724916)
			(end 1.1049 -0.724916)
			(stroke
				(width 0.1)
				(type default)
			)
			(layer "F.Fab")
		)
		(fp_line
			(start 1.1049 -0.724916)
			(end -1.1049 -0.724916)
			(stroke
				(width 0.1)
				(type default)
			)
			(layer "F.Fab")
		)
		(fp_line
			(start -1.1049 0.724916)
			(end 1.1049 0.724916)
			(stroke
				(width 0.1)
				(type default)
			)
			(layer "F.Fab")
		)
		(fp_line
			(start -1.1049 -0.724916)
			(end -1.1049 0.724916)
			(stroke
				(width 0.1)
				(type default)
			)
			(layer "F.Fab")
		)
		(pad "1" smd rect
			(at -0.889 0)
			(size 1.016 1.27)
			(layers "F.Cu" "F.Mask" "F.Paste")
			(net "PVCCIN_CPU1")
		)
		(pad "2" smd rect
			(at 0.889 0)
			(size 1.016 1.27)
			(layers "F.Cu" "F.Mask" "F.Paste")
			(net "GND")
		)
	)
)
